# T6G (Grand Teton) — schematic netlist excerpt (pin names and nets, part order shuffled) for the footprints in the layout excerpt that follows; sources: Cadence DE-HDL packaged netlist, KiCad conversion of 04192023_DAF0TMB3IC0_F0TG_MB_C_brd_V02_OCP.brd

J99  SCONN288_DDR506112002KQ  IO  pkg DDR288S_1-1VXC  page 108
  VIN_BULK0  = P12V_MEM_CPU1
  RFU0  = NC
  VIN_MGMT  = P3V3_AUX
  HSCL  = I3C_SPD_DDRK_CPU1_SCL
  HSDA  = I3C_SPD_DDRK_CPU1_SDA
  VSS0  = GND
  DQ0_A  = M_K_CPU1_SA_DQ<0>
  VSS1  = GND
  DQ1_A  = M_K_CPU1_SA_DQ<1>
  VSS2  = GND
  DQS0_A_T  = M_K_CPU1_SA_DQS_DP<0>
  DQS0_A_C  = M_K_CPU1_SA_DQS_DN<0>
  VSS3  = GND
  DQ4_A  = M_K_CPU1_SA_DQ<4>
  VSS4  = GND
  DQ5_A  = M_K_CPU1_SA_DQ<5>
  VSS5  = GND
  DQ8_A  = M_K_CPU1_SA_DQ<8>
  VSS6  = GND
  DQ9_A  = M_K_CPU1_SA_DQ<9>
  VSS7  = GND
  DQS1_A_T  = M_K_CPU1_SA_DQS_DP<1>
  DQS1_A_C  = M_K_CPU1_SA_DQS_DN<1>
  VSS8  = GND
  DQ12_A  = M_K_CPU1_SA_DQ<12>
  VSS9  = GND
  DQ13_A  = M_K_CPU1_SA_DQ<13>
  VSS10  = GND
  DQ16_A  = M_K_CPU1_SA_DQ<16>
  VSS11  = GND
  DQ17_A  = M_K_CPU1_SA_DQ<17>
  VSS12  = GND
  DQS2_A_T  = M_K_CPU1_SA_DQS_DP<2>
  DQS2_A_C  = M_K_CPU1_SA_DQS_DN<2>
  VSS13  = GND
  DQ20_A  = M_K_CPU1_SA_DQ<20>
  VSS14  = GND
  DQ21_A  = M_K_CPU1_SA_DQ<21>
  VSS15  = GND
  DQ24_A  = M_K_CPU1_SA_DQ<24>
  VSS16  = GND
  DQ25_A  = M_K_CPU1_SA_DQ<25>
  VSS17  = GND
  DQS3_A_T  = M_K_CPU1_SA_DQS_DP<3>
  DQS3_A_C  = M_K_CPU1_SA_DQS_DN<3>
  VSS18  = GND
  DQ28_A  = M_K_CPU1_SA_DQ<28>
  VSS19  = GND
  DQ29_A  = M_K_CPU1_SA_DQ<29>
  VSS20  = GND
  CB0_A  = M_K_CPU1_SA_CB<0>
  VSS21  = GND
  CB1_A  = M_K_CPU1_SA_CB<1>
  VSS22  = GND
  DQS4_A_T  = M_K_CPU1_SA_DQS_DP<4>
  DQS4_A_C  = M_K_CPU1_SA_DQS_DN<4>
  VSS23  = GND
  CB4_A  = M_K_CPU1_SA_CB<4>
  VSS24  = GND
  CB5_A  = M_K_CPU1_SA_CB<5>
  VSS25  = GND
  ALERT_N  = M_K_CPU1_ALERT_N
  VSS26  = GND
  CS0_A_N  = M_K_CPU1_SA_CS_N<0>
  VSS27  = GND
  CA0_A  = M_K_CPU1_SA_CA<0>
  VSS28  = GND
  CA2_A  = M_K_CPU1_SA_CA<2>
  VSS29  = GND
  CA4_A  = M_K_CPU1_SA_CA<4>
  VSS30  = GND
  CA6_A  = M_K_CPU1_SA_CA<6>
  VSS31  = GND
  PAR_A  = M_K_CPU1_SA_PAR
  VSS32  = GND
  CA0_B  = M_K_CPU1_SB_CA<0>
  VSS33  = GND
  CA2_B  = M_K_CPU1_SB_CA<2>
  VSS34  = GND
  CA4_B  = M_K_CPU1_SB_CA<4>
  VSS35  = GND
  CA6_B  = M_K_CPU1_SB_CA<6>
  VSS36  = GND
  CS0_B_N  = M_K_CPU1_SB_CS_N<0>
  VSS37  = GND
  \lbd||rsp_a_n\  = M_K_CPU1_SA_RSP<0>
  \lbs||rsp_b_n\  = M_K_CPU1_SB_RSP<0>
  VSS38  = GND
  CB4_B  = M_K_CPU1_SB_CB<4>
  VSS39  = GND
  CB5_B  = M_K_CPU1_SB_CB<5>
  VSS40  = GND
  \dqs9_b_t||tdqs9_b_t||dbi4_b_n\  = M_K_CPU1_SB_DQS_DP<9>
  \dqs9_b_c||tdqs9_b_c\  = M_K_CPU1_SB_DQS_DN<9>
  VSS41  = GND
  CB0_B  = M_K_CPU1_SB_CB<0>
  VSS42  = GND
  CB1_B  = M_K_CPU1_SB_CB<1>
  VSS43  = GND
  DQ0_B  = M_K_CPU1_SB_DQ<0>
  VSS44  = GND
  DQ1_B  = M_K_CPU1_SB_DQ<1>
  VSS45  = GND
  DQS0_B_T  = M_K_CPU1_SB_DQS_DP<0>
  DQS0_B_C  = M_K_CPU1_SB_DQS_DN<0>
  VSS46  = GND
  DQ4_B  = M_K_CPU1_SB_DQ<4>
  VSS47  = GND
  DQ5_B  = M_K_CPU1_SB_DQ<5>
  VSS48  = GND
  DQ8_B  = M_K_CPU1_SB_DQ<8>
  VSS49  = GND
  DQ9_B  = M_K_CPU1_SB_DQ<9>
  VSS50  = GND
  DQS1_B_T  = M_K_CPU1_SB_DQS_DP<1>
  DQS1_B_C  = M_K_CPU1_SB_DQS_DN<1>
  VSS51  = GND
  DQ12_B  = M_K_CPU1_SB_DQ<12>
  VSS52  = GND
  DQ13_B  = M_K_CPU1_SB_DQ<13>
  VSS53  = GND
  DQ16_B  = M_K_CPU1_SB_DQ<16>
  VSS54  = GND
  DQ17_B  = M_K_CPU1_SB_DQ<17>
  VSS55  = GND
  DQS2_B_T  = M_K_CPU1_SB_DQS_DP<2>
  DQS2_B_C  = M_K_CPU1_SB_DQS_DN<2>
  VSS56  = GND
  DQ20_B  = M_K_CPU1_SB_DQ<20>
  VSS57  = GND
  DQ21_B  = M_K_CPU1_SB_DQ<21>
  VSS58  = GND
  DQ24_B  = M_K_CPU1_SB_DQ<24>
  VSS59  = GND
  DQ25_B  = M_K_CPU1_SB_DQ<25>
  VSS60  = GND
  DQS3_B_T  = M_K_CPU1_SB_DQS_DP<3>
  DQS3_B_C  = M_K_CPU1_SB_DQS_DN<3>
  VSS61  = GND
  DQ28_B  = M_K_CPU1_SB_DQ<28>
  VSS62  = GND
  DQ29_B  = M_K_CPU1_SB_DQ<29>
  VSS63  = GND
  RFU1  = NC
  VIN_BULK1  = P12V_MEM_CPU1
  VIN_BULK2  = P12V_MEM_CPU1
  \pwr_good||fail_n\  = PWRGD_CHK_CPU1_DIMM
  HAS  = PD_CHK_CPU1_DIMM_SAA
  RFU2  = NC
  RFU3  = NC
  VSS64  = GND
  DQ2_A  = M_K_CPU1_SA_DQ<2>
  VSS65  = GND
  DQ3_A  = M_K_CPU1_SA_DQ<3>
  VSS66  = GND
  \dqs5_a_c||tdqs5_a_c||dqs5_a_t||tdqs5_a_t\  = M_K_CPU1_SA_DQS_DN<5>
  \dqs5_a_t||tdqs5_a_t\  = M_K_CPU1_SA_DQS_DP<5>
  VSS67  = GND
  DQ6_A  = M_K_CPU1_SA_DQ<6>
  VSS68  = GND
  DQ7_A  = M_K_CPU1_SA_DQ<7>
  VSS69  = GND
  DQ10_A  = M_K_CPU1_SA_DQ<10>
  VSS70  = GND
  DQ11_A  = M_K_CPU1_SA_DQ<11>
  VSS71  = GND
  \dqs6_a_c||tdqs6_a_c||dqs6_a_t||tdqs6_a_t\  = M_K_CPU1_SA_DQS_DN<6>
  \dqs6_a_t||tdqs6_a_t\  = M_K_CPU1_SA_DQS_DP<6>
  VSS72  = GND
  DQ14_A  = M_K_CPU1_SA_DQ<14>
  VSS73  = GND
  DQ15_A  = M_K_CPU1_SA_DQ<15>
  VSS74  = GND
  DQ18_A  = M_K_CPU1_SA_DQ<18>
  VSS75  = GND
  DQ19_A  = M_K_CPU1_SA_DQ<19>
  VSS76  = GND
  \dqs7_a_c||tdqs7_a_c\  = M_K_CPU1_SA_DQS_DN<7>
  \dqs7_a_t||tdqs7_a_t\  = M_K_CPU1_SA_DQS_DP<7>
  VSS77  = GND
  DQ22_A  = M_K_CPU1_SA_DQ<22>
  VSS78  = GND
  DQ23_A  = M_K_CPU1_SA_DQ<23>
  VSS79  = GND
  DQ26_A  = M_K_CPU1_SA_DQ<26>
  VSS80  = GND
  DQ27_A  = M_K_CPU1_SA_DQ<27>
  VSS81  = GND
  \dqs8_a_c||tdqs8_a_c\  = M_K_CPU1_SA_DQS_DN<8>
  \dqs8_a_t||tdqs8_a_t\  = M_K_CPU1_SA_DQS_DP<8>
  VSS82  = GND
  DQ30_A  = M_K_CPU1_SA_DQ<30>
  VSS83  = GND
  DQ31_A  = M_K_CPU1_SA_DQ<31>
  VSS84  = GND
  CB2_A  = M_K_CPU1_SA_CB<2>
  VSS85  = GND
  CB3_A  = M_K_CPU1_SA_CB<3>
  VSS86  = GND
  \dqs9_a_c||tdqs9_a_c\  = M_K_CPU1_SA_DQS_DN<9>
  \dqs9_a_t||tdqs9_a_t\  = M_K_CPU1_SA_DQS_DP<9>
  VSS87  = GND
  CB6_A  = M_K_CPU1_SA_CB<6>
  VSS88  = GND
  CB7_A  = M_K_CPU1_SA_CB<7>
  VSS89  = GND
  RESET_N  = M_K_CPU1_RESET_N
  VSS90  = GND
  CS1_A_N  = M_K_CPU1_SA_CS_N<1>
  VSS91  = GND
  CA1_A  = M_K_CPU1_SA_CA<1>
  VSS92  = GND
  CA3_A  = M_K_CPU1_SA_CA<3>
  VSS93  = GND
  CA5_A  = M_K_CPU1_SA_CA<5>
  VSS94  = GND
  CK_T  = M_K_CPU1_CLK_DP<0>
  CK_C  = M_K_CPU1_CLK_DN<0>
  VSS95  = GND
  RFU4  = NC
  CA1_B  = M_K_CPU1_SB_CA<1>
  VSS96  = GND
  CA3_B  = M_K_CPU1_SB_CA<3>
  VSS97  = GND
  CA5_B  = M_K_CPU1_SB_CA<5>
  VSS98  = GND
  PAR_B  = M_K_CPU1_SB_PAR
  VSS99  = GND
  CS1_B_N  = M_K_CPU1_SB_CS_N<1>
  VSS100  = GND
  RFU5  = NC
  RFU6  = NC
  VSS101  = GND
  CB6_B  = M_K_CPU1_SB_CB<6>
  VSS102  = GND
  CB7_B  = M_K_CPU1_SB_CB<7>
  VSS103  = GND
  DQS4_B_C  = M_K_CPU1_SB_DQS_DN<4>
  DQS4_B_T  = M_K_CPU1_SB_DQS_DP<4>
  VSS104  = GND
  CB2_B  = M_K_CPU1_SB_CB<2>
  VSS105  = GND
  CB3_B  = M_K_CPU1_SB_CB<3>
  VSS106  = GND
  DQ2_B  = M_K_CPU1_SB_DQ<2>
  VSS107  = GND
  DQ3_B  = M_K_CPU1_SB_DQ<3>
  VSS108  = GND
  \dqs5_b_c||tdqs5_b_c\  = M_K_CPU1_SB_DQS_DN<5>
  \dqs5_b_t||tdqs5_b_t\  = M_K_CPU1_SB_DQS_DP<5>
  VSS109  = GND
  DQ6_B  = M_K_CPU1_SB_DQ<6>
  VSS110  = GND
  DQ7_B  = M_K_CPU1_SB_DQ<7>
  VSS111  = GND
  DQ10_B  = M_K_CPU1_SB_DQ<10>
  VSS112  = GND
  DQ11_B  = M_K_CPU1_SB_DQ<11>
  VSS113  = GND
  \dqs6_b_c||tdqs6_b_c\  = M_K_CPU1_SB_DQS_DN<6>
  \dqs6_b_t||tdqs6_b_t\  = M_K_CPU1_SB_DQS_DP<6>
  VSS114  = GND
  DQ14_B  = M_K_CPU1_SB_DQ<14>
  VSS115  = GND
  DQ15_B  = M_K_CPU1_SB_DQ<15>
  VSS116  = GND
  DQ18_B  = M_K_CPU1_SB_DQ<18>
  VSS117  = GND
  DQ19_B  = M_K_CPU1_SB_DQ<19>
  VSS118  = GND
  \dqs7_b_c||tdqs7_b_c\  = M_K_CPU1_SB_DQS_DN<7>
  \dqs7_b_t||tdqs7_b_t\  = M_K_CPU1_SB_DQS_DP<7>
  VSS119  = GND
  DQ22_B  = M_K_CPU1_SB_DQ<22>
  VSS120  = GND
  DQ23_B  = M_K_CPU1_SB_DQ<23>
  VSS121  = GND
  DQ26_B  = M_K_CPU1_SB_DQ<26>
  VSS122  = GND
  DQ27_B  = M_K_CPU1_SB_DQ<27>
  VSS123  = GND
  \dqs8_b_c||tdqs8_b_c\  = M_K_CPU1_SB_DQS_DN<8>
  \dqs8_b_t||tdqs8_b_t\  = M_K_CPU1_SB_DQS_DP<8>
  VSS124  = GND
  DQ30_B  = M_K_CPU1_SB_DQ<30>
  VSS125  = GND
  DQ31_B  = M_K_CPU1_SB_DQ<31>
  VSS126  = GND
  G1  = GND
  G2  = GND
  G3  = GND

(kicad_pcb
	(version 20260206)
	(generator "pcbnew")
	(generator_version "10.0")
	(general
		(thickness 1.6)
		(legacy_teardrops no)
	)
	(paper "A4")
	(title_block
		(title "04192023_DAF0TMB3IC0_F0TG_MB_C_brd_V02_OCP.brd")
		(comment 1 "Grand Teton / footprint 4555 of 8354 (J99), pads 185-230 of 291")
	)
	(layers
		(0 "F.Cu" signal "TOP")
		(4 "In1.Cu" signal "GND")
		(6 "In2.Cu" signal "IN1")
		(8 "In3.Cu" signal "GND1")
		(10 "In4.Cu" signal "IN2")
		(12 "In5.Cu" signal "GND2")
		(14 "In6.Cu" signal "IN3")
		(16 "In7.Cu" signal "GND3")
		(18 "In8.Cu" signal "VCC")
		(20 "In9.Cu" signal "VCC1")
		(22 "In10.Cu" signal "GND4")
		(24 "In11.Cu" signal "IN4")
		(26 "In12.Cu" signal "GND5")
		(28 "In13.Cu" signal "IN5")
		(30 "In14.Cu" signal "GND6")
		(32 "In15.Cu" signal "IN6")
		(34 "In16.Cu" signal "GND7")
		(2 "B.Cu" signal "BOTTOM")
		(9 "F.Adhes" user "F.Adhesive")
		(11 "B.Adhes" user "B.Adhesive")
		(13 "F.Paste" user "Package Geometry/Pastemask Top")
		(15 "B.Paste" user "Package Geometry/Pastemask Bottom")
		(5 "F.SilkS" user "Ref Des/Silkscreen Top")
		(7 "B.SilkS" user "Ref Des/Silkscreen Bottom")
		(1 "F.Mask" user "Board Geometry/Soldermask Top")
		(3 "B.Mask" user "Board Geometry/Soldermask Bottom")
		(17 "Dwgs.User" user "User.Drawings")
		(19 "Cmts.User" user "User.Comments")
		(21 "Eco1.User" user "User.Eco1")
		(23 "Eco2.User" user "User.Eco2")
		(25 "Edge.Cuts" user "Board Geometry/Outline")
		(27 "Margin" user)
		(31 "F.CrtYd" user "Package Geometry/Place Bound Top")
		(29 "B.CrtYd" user "Package Geometry/Place Bound Bottom")
		(35 "F.Fab" user "Ref Des/Assembly Top")
		(33 "B.Fab" user "Ref Des/Assembly Bottom")
	)
	(footprint ""
		(layer "F.Cu")
		(at 196.654166 -255.560322 180)
		(property "Reference" "J99"
			(at -0.4318 -81.730088 0)
			(unlocked yes)
			(layer "F.SilkS")
			(effects
				(font
					(size 0.7874 0.5842)
					(thickness 0.1524)
				)
			)
		)
		(property "Value" ""
			(at 0 0 180)
			(layer "F.Fab")
			(effects
				(font
					(size 1.27 1.27)
				)
			)
		)
		(duplicate_pad_numbers_are_jumpers no)
		(pad "185" smd rect
			(at 2.050034 -29.325062 90)
			(size 0.519938 1.4986)
			(layers "F.Cu" "F.Mask" "F.Paste")
			(net "M_K_CPU1_SA_DQ<26>")
		)
		(pad "186" smd rect
			(at 2.050034 -28.474924 90)
			(size 0.519938 1.4986)
			(layers "F.Cu" "F.Mask" "F.Paste")
			(net "GND")
		)
		(pad "187" smd rect
			(at 2.050034 -27.62504 90)
			(size 0.519938 1.4986)
			(layers "F.Cu" "F.Mask" "F.Paste")
			(net "M_K_CPU1_SA_DQ<27>")
		)
		(pad "188" smd rect
			(at 2.050034 -26.774902 90)
			(size 0.519938 1.4986)
			(layers "F.Cu" "F.Mask" "F.Paste")
			(net "GND")
		)
		(pad "189" smd rect
			(at 2.050034 -25.925018 90)
			(size 0.519938 1.4986)
			(layers "F.Cu" "F.Mask" "F.Paste")
			(net "M_K_CPU1_SA_DQS_DN<8>")
		)
		(pad "190" smd rect
			(at 2.050034 -25.07488 90)
			(size 0.519938 1.4986)
			(layers "F.Cu" "F.Mask" "F.Paste")
			(net "M_K_CPU1_SA_DQS_DP<8>")
		)
		(pad "191" smd rect
			(at 2.050034 -24.224996 90)
			(size 0.519938 1.4986)
			(layers "F.Cu" "F.Mask" "F.Paste")
			(net "GND")
		)
		(pad "192" smd rect
			(at 2.050034 -23.375112 90)
			(size 0.519938 1.4986)
			(layers "F.Cu" "F.Mask" "F.Paste")
			(net "M_K_CPU1_SA_DQ<30>")
		)
		(pad "193" smd rect
			(at 2.050034 -22.524974 90)
			(size 0.519938 1.4986)
			(layers "F.Cu" "F.Mask" "F.Paste")
			(net "GND")
		)
		(pad "194" smd rect
			(at 2.050034 -21.67509 90)
			(size 0.519938 1.4986)
			(layers "F.Cu" "F.Mask" "F.Paste")
			(net "M_K_CPU1_SA_DQ<31>")
		)
		(pad "195" smd rect
			(at 2.050034 -20.824952 90)
			(size 0.519938 1.4986)
			(layers "F.Cu" "F.Mask" "F.Paste")
			(net "GND")
		)
		(pad "196" smd rect
			(at 2.050034 -19.975068 90)
			(size 0.519938 1.4986)
			(layers "F.Cu" "F.Mask" "F.Paste")
			(net "M_K_CPU1_SA_CB<2>")
		)
		(pad "197" smd rect
			(at 2.050034 -19.12493 90)
			(size 0.519938 1.4986)
			(layers "F.Cu" "F.Mask" "F.Paste")
			(net "GND")
		)
		(pad "198" smd rect
			(at 2.050034 -18.275046 90)
			(size 0.519938 1.4986)
			(layers "F.Cu" "F.Mask" "F.Paste")
			(net "M_K_CPU1_SA_CB<3>")
		)
		(pad "199" smd rect
			(at 2.050034 -17.424908 90)
			(size 0.519938 1.4986)
			(layers "F.Cu" "F.Mask" "F.Paste")
			(net "GND")
		)
		(pad "200" smd rect
			(at 2.050034 -16.575024 90)
			(size 0.519938 1.4986)
			(layers "F.Cu" "F.Mask" "F.Paste")
			(net "M_K_CPU1_SA_DQS_DN<9>")
		)
		(pad "201" smd rect
			(at 2.050034 -15.724886 90)
			(size 0.519938 1.4986)
			(layers "F.Cu" "F.Mask" "F.Paste")
			(net "M_K_CPU1_SA_DQS_DP<9>")
		)
		(pad "202" smd rect
			(at 2.050034 -14.875002 90)
			(size 0.519938 1.4986)
			(layers "F.Cu" "F.Mask" "F.Paste")
			(net "GND")
		)
		(pad "203" smd rect
			(at 2.050034 -14.025118 90)
			(size 0.519938 1.4986)
			(layers "F.Cu" "F.Mask" "F.Paste")
			(net "M_K_CPU1_SA_CB<6>")
		)
		(pad "204" smd rect
			(at 2.050034 -13.17498 90)
			(size 0.519938 1.4986)
			(layers "F.Cu" "F.Mask" "F.Paste")
			(net "GND")
		)
		(pad "205" smd rect
			(at 2.050034 -12.325096 90)
			(size 0.519938 1.4986)
			(layers "F.Cu" "F.Mask" "F.Paste")
			(net "M_K_CPU1_SA_CB<7>")
		)
		(pad "206" smd rect
			(at 2.050034 -11.474958 90)
			(size 0.519938 1.4986)
			(layers "F.Cu" "F.Mask" "F.Paste")
			(net "GND")
		)
		(pad "207" smd rect
			(at 2.050034 -10.625074 90)
			(size 0.519938 1.4986)
			(layers "F.Cu" "F.Mask" "F.Paste")
			(net "M_K_CPU1_RESET_N")
		)
		(pad "208" smd rect
			(at 2.050034 -9.774936 90)
			(size 0.519938 1.4986)
			(layers "F.Cu" "F.Mask" "F.Paste")
			(net "GND")
		)
		(pad "209" smd rect
			(at 2.050034 -8.925052 90)
			(size 0.519938 1.4986)
			(layers "F.Cu" "F.Mask" "F.Paste")
			(net "M_K_CPU1_SA_CS_N<1>")
		)
		(pad "210" smd rect
			(at 2.050034 -8.074914 90)
			(size 0.519938 1.4986)
			(layers "F.Cu" "F.Mask" "F.Paste")
			(net "GND")
		)
		(pad "211" smd rect
			(at 2.050034 -7.22503 90)
			(size 0.519938 1.4986)
			(layers "F.Cu" "F.Mask" "F.Paste")
			(net "M_K_CPU1_SA_CA<1>")
		)
		(pad "212" smd rect
			(at 2.050034 -6.374892 90)
			(size 0.519938 1.4986)
			(layers "F.Cu" "F.Mask" "F.Paste")
			(net "GND")
		)
		(pad "213" smd rect
			(at 2.050034 -5.525008 90)
			(size 0.519938 1.4986)
			(layers "F.Cu" "F.Mask" "F.Paste")
			(net "M_K_CPU1_SA_CA<3>")
		)
		(pad "214" smd rect
			(at 2.050034 -4.675124 90)
			(size 0.519938 1.4986)
			(layers "F.Cu" "F.Mask" "F.Paste")
			(net "GND")
		)
		(pad "215" smd rect
			(at 2.050034 -3.824986 90)
			(size 0.519938 1.4986)
			(layers "F.Cu" "F.Mask" "F.Paste")
			(net "M_K_CPU1_SA_CA<5>")
		)
		(pad "216" smd rect
			(at 2.050034 -2.975102 90)
			(size 0.519938 1.4986)
			(layers "F.Cu" "F.Mask" "F.Paste")
			(net "GND")
		)
		(pad "217" smd rect
			(at 2.050034 -2.124964 90)
			(size 0.519938 1.4986)
			(layers "F.Cu" "F.Mask" "F.Paste")
			(net "M_K_CPU1_CLK_DP<0>")
		)
		(pad "218" smd rect
			(at 2.050034 -1.27508 90)
			(size 0.519938 1.4986)
			(layers "F.Cu" "F.Mask" "F.Paste")
			(net "M_K_CPU1_CLK_DN<0>")
		)
		(pad "219" smd rect
			(at 2.050034 -0.424942 90)
			(size 0.519938 1.4986)
			(layers "F.Cu" "F.Mask" "F.Paste")
			(net "GND")
		)
		(pad "220" smd rect
			(at 2.050034 5.525008 90)
			(size 0.519938 1.4986)
			(layers "F.Cu" "F.Mask" "F.Paste")
			(net "Net_2400")
		)
		(pad "221" smd rect
			(at 2.050034 6.374892 90)
			(size 0.519938 1.4986)
			(layers "F.Cu" "F.Mask" "F.Paste")
			(net "M_K_CPU1_SB_CA<1>")
		)
		(pad "222" smd rect
			(at 2.050034 7.22503 90)
			(size 0.519938 1.4986)
			(layers "F.Cu" "F.Mask" "F.Paste")
			(net "GND")
		)
		(pad "223" smd rect
			(at 2.050034 8.074914 90)
			(size 0.519938 1.4986)
			(layers "F.Cu" "F.Mask" "F.Paste")
			(net "M_K_CPU1_SB_CA<3>")
		)
		(pad "224" smd rect
			(at 2.050034 8.925052 90)
			(size 0.519938 1.4986)
			(layers "F.Cu" "F.Mask" "F.Paste")
			(net "GND")
		)
		(pad "225" smd rect
			(at 2.050034 9.774936 90)
			(size 0.519938 1.4986)
			(layers "F.Cu" "F.Mask" "F.Paste")
			(net "M_K_CPU1_SB_CA<5>")
		)
		(pad "226" smd rect
			(at 2.050034 10.625074 90)
			(size 0.519938 1.4986)
			(layers "F.Cu" "F.Mask" "F.Paste")
			(net "GND")
		)
		(pad "227" smd rect
			(at 2.050034 11.474958 90)
			(size 0.519938 1.4986)
			(layers "F.Cu" "F.Mask" "F.Paste")
			(net "M_K_CPU1_SB_PAR")
		)
		(pad "228" smd rect
			(at 2.050034 12.325096 90)
			(size 0.519938 1.4986)
			(layers "F.Cu" "F.Mask" "F.Paste")
			(net "GND")
		)
		(pad "229" smd rect
			(at 2.050034 13.17498 90)
			(size 0.519938 1.4986)
			(layers "F.Cu" "F.Mask" "F.Paste")
			(net "M_K_CPU1_SB_CS_N<1>")
		)
		(pad "230" smd rect
			(at 2.050034 14.025118 90)
			(size 0.519938 1.4986)
			(layers "F.Cu" "F.Mask" "F.Paste")
			(net "GND")
		)
	)
)
